# BASEBOARD_FAB2 (Tioga Pass) — schematic netlist excerpt (pin names and nets, part order shuffled) for the footprints in the layout excerpt that follows; sources: Cadence DE-HDL packaged netlist, KiCad conversion of Wiwynn_Tioga_Pass_MB.brd

C6R7  CAP_A  22.0UF 4V 20% X6S  pkg 0603V  page 202 : A = PVCCIN_CPU0 ; B = GND
R1L19  RES  4.75K 1% CHIP  pkg 0402  page 175 : A = P3V3_STBY ; B = FM_DEBUG_RST_BTN_N
C25W11  CAP_A  0.01UF 25V 10% X7R  pkg 0402V  page 151 : A = BMC_M_VREFCA ; B = GND

(kicad_pcb
	(version 20260206)
	(generator "pcbnew")
	(generator_version "10.0")
	(general
		(thickness 1.6)
		(legacy_teardrops no)
	)
	(paper "A4")
	(title_block
		(title "Wiwynn_Tioga_Pass_MB.brd")
		(comment 1 "Tioga Pass / footprints 2775-2777 of 4770")
	)
	(layers
		(0 "F.Cu" signal "TOP")
		(4 "In1.Cu" signal "L2GND")
		(6 "In2.Cu" signal "L3")
		(8 "In3.Cu" signal "L4GND")
		(10 "In4.Cu" signal "L5")
		(12 "In5.Cu" signal "L6GND")
		(14 "In6.Cu" signal "L7VCC")
		(16 "In7.Cu" signal "L8VCC")
		(18 "In8.Cu" signal "L9GND")
		(20 "In9.Cu" signal "L10")
		(22 "In10.Cu" signal "L11GND")
		(24 "In11.Cu" signal "L12")
		(26 "In12.Cu" signal "L13GND")
		(2 "B.Cu" signal "BOTTOM")
		(9 "F.Adhes" user "F.Adhesive")
		(11 "B.Adhes" user "B.Adhesive")
		(13 "F.Paste" user "Package Geometry/Pastemask Top")
		(15 "B.Paste" user "Package Geometry/Pastemask Bottom")
		(5 "F.SilkS" user "Ref Des/Silkscreen Top")
		(7 "B.SilkS" user "Ref Des/Silkscreen Bottom")
		(1 "F.Mask" user "Board Geometry/Soldermask Top")
		(3 "B.Mask" user "Board Geometry/Soldermask Bottom")
		(17 "Dwgs.User" user "User.Drawings")
		(19 "Cmts.User" user "User.Comments")
		(21 "Eco1.User" user "User.Eco1")
		(23 "Eco2.User" user "User.Eco2")
		(25 "Edge.Cuts" user "Board Geometry/Outline")
		(27 "Margin" user)
		(31 "F.CrtYd" user "Package Geometry/Place Bound Top")
		(29 "B.CrtYd" user "Package Geometry/Place Bound Bottom")
		(35 "F.Fab" user "Ref Des/Assembly Top")
		(33 "B.Fab" user "Ref Des/Assembly Bottom")
	)
	(footprint ""
		(layer "B.Cu")
		(at 489.26496 -151.06904 90)
		(property "Reference" "R1L19"
			(at 0 0 90)
			(layer "B.SilkS")
			(hide yes)
			(effects
				(font
					(size 1.27 1.27)
				)
				(justify mirror)
			)
		)
		(property "Value" ""
			(at 0 0 90)
			(layer "B.Fab")
			(effects
				(font
					(size 1.27 1.27)
				)
				(justify mirror)
			)
		)
		(duplicate_pad_numbers_are_jumpers no)
		(fp_poly
			(pts
				(xy 0.2794 -0.1016) (xy -0.2794 -0.1016) (xy -0.2794 0.9906) (xy 0.2794 0.9906)
			)
			(stroke
				(width 0)
				(type default)
			)
			(fill no)
			(layer "B.CrtYd")
		)
		(fp_line
			(start 0.2794 -0.1016)
			(end 0.2794 0.9906)
			(stroke
				(width 0.1)
				(type default)
			)
			(layer "B.Fab")
		)
		(fp_line
			(start -0.2794 -0.1016)
			(end 0.2794 -0.1016)
			(stroke
				(width 0.1)
				(type default)
			)
			(layer "B.Fab")
		)
		(fp_line
			(start 0.2794 0.9906)
			(end -0.2794 0.9906)
			(stroke
				(width 0.1)
				(type default)
			)
			(layer "B.Fab")
		)
		(fp_line
			(start -0.2794 0.9906)
			(end -0.2794 -0.1016)
			(stroke
				(width 0.1)
				(type default)
			)
			(layer "B.Fab")
		)
		(pad "1" smd rect
			(at 0 0 270)
			(size 0.508 0.508)
			(layers "B.Cu" "B.Mask" "B.Paste")
			(net "P3V3_STBY")
		)
		(pad "2" smd rect
			(at 0 0.889 270)
			(size 0.508 0.508)
			(layers "B.Cu" "B.Mask" "B.Paste")
			(net "FM_DEBUG_RST_BTN_N")
		)
		(zone
			(layer "B.Cu")
			(hatch none 0.5)
			(connect_pads
				(clearance 0)
			)
			(min_thickness 0.25)
			(keepout
				(tracks allowed)
				(vias not_allowed)
				(pads allowed)
				(copperpour not_allowed)
				(footprints allowed)
			)
			(placement
				(enabled no)
				(sheetname "")
			)
			(fill
				(thermal_gap 0.5)
				(thermal_bridge_width 0.5)
				(island_removal_mode 0)
			)
			(polygon
				(pts
					(xy 489.51896 -151.32304) (xy 489.51896 -150.81504) (xy 489.89996 -150.81504) (xy 489.89996 -151.32304)
				)
			)
		)
		(zone
			(layer "B.Cu")
			(hatch none 0.5)
			(connect_pads
				(clearance 0)
			)
			(min_thickness 0.25)
			(keepout
				(tracks not_allowed)
				(vias allowed)
				(pads allowed)
				(copperpour not_allowed)
				(footprints allowed)
			)
			(placement
				(enabled no)
				(sheetname "")
			)
			(fill
				(thermal_gap 0.5)
				(thermal_bridge_width 0.5)
				(island_removal_mode 0)
			)
			(polygon
				(pts
					(xy 489.89996 -151.32304) (xy 489.89996 -150.81504) (xy 489.51896 -150.81504) (xy 489.51896 -151.32304)
				)
			)
		)
	)
	(footprint ""
		(layer "B.Cu")
		(at 214.503 -59.17692 180)
		(property "Reference" "C6R7"
			(at 0 0 0)
			(layer "B.SilkS")
			(hide yes)
			(effects
				(font
					(size 1.27 1.27)
				)
				(justify mirror)
			)
		)
		(property "Value" ""
			(at 0 0 0)
			(layer "B.Fab")
			(effects
				(font
					(size 1.27 1.27)
				)
				(justify mirror)
			)
		)
		(duplicate_pad_numbers_are_jumpers no)
		(fp_poly
			(pts
				(xy 0.4953 -0.2032) (xy -0.4953 -0.2032) (xy -0.4953 1.6002) (xy 0.4953 1.6002)
			)
			(stroke
				(width 0)
				(type default)
			)
			(fill no)
			(layer "B.CrtYd")
		)
		(fp_line
			(start 0.4953 1.6002)
			(end 0.4953 -0.2032)
			(stroke
				(width 0.1)
				(type default)
			)
			(layer "B.Fab")
		)
		(fp_line
			(start 0.4953 -0.2032)
			(end -0.4953 -0.2032)
			(stroke
				(width 0.1)
				(type default)
			)
			(layer "B.Fab")
		)
		(fp_line
			(start -0.4953 1.6002)
			(end 0.4953 1.6002)
			(stroke
				(width 0.1)
				(type default)
			)
			(layer "B.Fab")
		)
		(fp_line
			(start -0.4953 -0.2032)
			(end -0.4953 1.6002)
			(stroke
				(width 0.1)
				(type default)
			)
			(layer "B.Fab")
		)
		(pad "1" smd rect
			(at 0 0)
			(size 0.762 0.889)
			(layers "B.Cu" "B.Mask" "B.Paste")
			(net "PVCCIN_CPU0")
		)
		(pad "2" smd rect
			(at 0 1.397)
			(size 0.762 0.889)
			(layers "B.Cu" "B.Mask" "B.Paste")
			(net "GND")
		)
		(zone
			(layer "B.Cu")
			(hatch none 0.5)
			(connect_pads
				(clearance 0)
			)
			(min_thickness 0.25)
			(keepout
				(tracks not_allowed)
				(vias allowed)
				(pads allowed)
				(copperpour not_allowed)
				(footprints allowed)
			)
			(placement
				(enabled no)
				(sheetname "")
			)
			(fill
				(thermal_gap 0.5)
				(thermal_bridge_width 0.5)
				(island_removal_mode 0)
			)
			(polygon
				(pts
					(xy 214.122 -59.62142) (xy 214.884 -59.62142) (xy 214.884 -60.12942) (xy 214.122 -60.12942)
				)
			)
		)
	)
	(footprint ""
		(layer "B.Cu")
		(at 446.53835 -29.6164)
		(property "Reference" "C25W11"
			(at 0.8382 -0.67818 0)
			(unlocked yes)
			(layer "B.SilkS")
			(effects
				(font
					(size 0.4064 0.254)
					(thickness 0.1524)
				)
				(justify left mirror)
			)
		)
		(property "Value" ""
			(at 0 0 0)
			(layer "B.Fab")
			(effects
				(font
					(size 1.27 1.27)
				)
				(justify mirror)
			)
		)
		(duplicate_pad_numbers_are_jumpers no)
		(fp_poly
			(pts
				(xy -0.3048 -0.1016) (xy -0.3048 0.9906) (xy 0.3048 0.9906) (xy 0.3048 -0.1016)
			)
			(stroke
				(width 0)
				(type default)
			)
			(fill no)
			(layer "B.CrtYd")
		)
		(fp_line
			(start -0.3048 -0.1016)
			(end 0.3048 -0.1016)
			(stroke
				(width 0.1)
				(type default)
			)
			(layer "B.Fab")
		)
		(fp_line
			(start -0.3048 0.9906)
			(end -0.3048 -0.1016)
			(stroke
				(width 0.1)
				(type default)
			)
			(layer "B.Fab")
		)
		(fp_line
			(start 0.3048 -0.1016)
			(end 0.3048 0.9906)
			(stroke
				(width 0.1)
				(type default)
			)
			(layer "B.Fab")
		)
		(fp_line
			(start 0.3048 0.9906)
			(end -0.3048 0.9906)
			(stroke
				(width 0.1)
				(type default)
			)
			(layer "B.Fab")
		)
		(pad "1" smd rect
			(at 0 0 180)
			(size 0.508 0.508)
			(layers "B.Cu" "B.Mask" "B.Paste")
			(net "BMC_M_VREFCA")
		)
		(pad "2" smd rect
			(at 0 0.889 180)
			(size 0.508 0.508)
			(layers "B.Cu" "B.Mask" "B.Paste")
			(net "GND")
		)
		(zone
			(layer "B.Cu")
			(hatch none 0.5)
			(connect_pads
				(clearance 0)
			)
			(min_thickness 0.25)
			(keepout
				(tracks allowed)
				(vias not_allowed)
				(pads allowed)
				(copperpour not_allowed)
				(footprints allowed)
			)
			(placement
				(enabled no)
				(sheetname "")
			)
			(fill
				(thermal_gap 0.5)
				(thermal_bridge_width 0.5)
				(island_removal_mode 0)
			)
			(polygon
				(pts
					(xy 446.79235 -29.3624) (xy 446.28435 -29.3624) (xy 446.28435 -28.9814) (xy 446.79235 -28.9814)
				)
			)
		)
		(zone
			(layer "B.Cu")
			(hatch none 0.5)
			(connect_pads
				(clearance 0)
			)
			(min_thickness 0.25)
			(keepout
				(tracks not_allowed)
				(vias allowed)
				(pads allowed)
				(copperpour not_allowed)
				(footprints allowed)
			)
			(placement
				(enabled no)
				(sheetname "")
			)
			(fill
				(thermal_gap 0.5)
				(thermal_bridge_width 0.5)
				(island_removal_mode 0)
			)
			(polygon
				(pts
					(xy 446.79235 -28.9814) (xy 446.28435 -28.9814) (xy 446.28435 -29.3624) (xy 446.79235 -29.3624)
				)
			)
		)
	)
)
